(kicad_pcb
	(version 20241229)
	(generator "pcbnew")
	(generator_version "9.0")
	(general
		(thickness 1.63)
		(legacy_teardrops no)
	)
	(paper "A4")
	(title_block
		(title "CM4 Baseboard")
		(date "2026-01-05")
		(rev "1.1.1")
		(company "Antmicro Ltd")
		(comment 1 "www.antmicro.com")
		(comment 9 "footprints 246-251 of 506")
	)
	(layers
		(0 "F.Cu" signal)
		(4 "In1.Cu" power)
		(6 "In2.Cu" power)
		(8 "In3.Cu" signal)
		(10 "In4.Cu" signal)
		(2 "B.Cu" signal)
		(9 "F.Adhes" user "F.Adhesive")
		(11 "B.Adhes" user "B.Adhesive")
		(13 "F.Paste" user)
		(15 "B.Paste" user)
		(5 "F.SilkS" user "F.Silkscreen")
		(7 "B.SilkS" user "B.Silkscreen")
		(1 "F.Mask" user)
		(3 "B.Mask" user)
		(17 "Dwgs.User" user "User.Drawings")
		(19 "Cmts.User" user "User.Comments")
		(21 "Eco1.User" user "User.Eco1")
		(23 "Eco2.User" user "User.Eco2")
		(25 "Edge.Cuts" user)
		(27 "Margin" user)
		(31 "F.CrtYd" user "F.Courtyard")
		(29 "B.CrtYd" user "B.Courtyard")
		(35 "F.Fab" user)
		(33 "B.Fab" user)
	)
	(footprint "antmicro-footprints:C_0402_1005Metric"
		(layer "F.Cu")
		(at 63.617962 178.2005 180)
		(descr "Capacitor SMD 0402")
		(tags "capacitor SMD 0402")
		(property "Reference" "C821"
			(at 13.367962 1.4505 0)
			(layer "F.SilkS")
			(effects
				(font
					(size 0.7 0.7)
					(thickness 0.15)
				)
				(justify right top)
			)
		)
		(property "Value" "C_36p_0402"
			(at -1.022927 2.155213 0)
			(layer "F.Fab")
			(effects
				(font
					(size 0.7 0.7)
					(thickness 0.15)
				)
				(justify right top)
			)
		)
		(property "Datasheet" "https://eu.mouser.com/datasheet/3/5926/1/C0GNP0_Dielectric.pdf"
			(at 0 0 0)
			(layer "F.Fab")
			(hide yes)
			(effects
				(font
					(size 1.27 1.27)
					(thickness 0.15)
				)
			)
		)
		(property "Description" "Multilayer Ceramic Capacitors MLCC, 36 pF, 25V, 0402, C0G, 5%"
			(at 0 0 0)
			(layer "F.Fab")
			(hide yes)
			(effects
				(font
					(size 1.27 1.27)
					(thickness 0.15)
				)
			)
		)
		(property "MPN" "04023A360JAT2A"
			(at 0 0 180)
			(unlocked yes)
			(layer "F.Fab")
			(hide yes)
			(effects
				(font
					(size 1 1)
					(thickness 0.15)
				)
			)
		)
		(property "Manufacturer" "KYOCERA AVX"
			(at 0 0 180)
			(unlocked yes)
			(layer "F.Fab")
			(hide yes)
			(effects
				(font
					(size 1 1)
					(thickness 0.15)
				)
			)
		)
		(property "License" "Apache-2.0"
			(at 0 0 180)
			(unlocked yes)
			(layer "F.Fab")
			(hide yes)
			(effects
				(font
					(size 1 1)
					(thickness 0.15)
				)
			)
		)
		(property "Author" "Antmicro"
			(at 0 0 180)
			(unlocked yes)
			(layer "F.Fab")
			(hide yes)
			(effects
				(font
					(size 1 1)
					(thickness 0.15)
				)
			)
		)
		(property "Val" "36pF"
			(at 0 0 180)
			(unlocked yes)
			(layer "F.Fab")
			(hide yes)
			(effects
				(font
					(size 1 1)
					(thickness 0.15)
				)
			)
		)
		(property "Voltage" "25 V"
			(at 0 0 180)
			(unlocked yes)
			(layer "F.Fab")
			(hide yes)
			(effects
				(font
					(size 1 1)
					(thickness 0.15)
				)
			)
		)
		(property "Dielectric" "C0G (NP0)"
			(at 0 0 180)
			(unlocked yes)
			(layer "F.Fab")
			(hide yes)
			(effects
				(font
					(size 1 1)
					(thickness 0.15)
				)
			)
		)
		(sheetname "/Peripherals/")
		(sheetfile "peripherals.kicad_sch")
		(attr smd)
		(fp_rect
			(start -0.925 -0.47)
			(end 0.925 0.47)
			(stroke
				(width 0.05)
				(type default)
			)
			(fill no)
			(layer "F.CrtYd")
		)
		(fp_line
			(start 0.504 0.248)
			(end -0.494 0.248)
			(stroke
				(width 0.15)
				(type solid)
			)
			(layer "F.Fab")
		)
		(fp_line
			(start 0.504 -0.25)
			(end 0.504 0.248)
			(stroke
				(width 0.15)
				(type solid)
			)
			(layer "F.Fab")
		)
		(fp_line
			(start -0.494 0.248)
			(end -0.494 -0.25)
			(stroke
				(width 0.15)
				(type solid)
			)
			(layer "F.Fab")
		)
		(fp_line
			(start -0.494 -0.25)
			(end 0.504 -0.25)
			(stroke
				(width 0.15)
				(type solid)
			)
			(layer "F.Fab")
		)
		(fp_text user "Author: Antmicro"
			(at -0.939 3.399 0)
			(layer "F.Fab")
			(effects
				(font
					(size 0.7 0.7)
					(thickness 0.15)
				)
				(justify right top)
			)
		)
		(fp_text user "License: Apache-2.0"
			(at -0.939 5.799 0)
			(layer "F.Fab")
			(effects
				(font
					(size 0.7 0.7)
					(thickness 0.15)
				)
				(justify right top)
			)
		)
		(fp_text user "${REFERENCE}"
			(at -0.939 4.599 0)
			(layer "F.Fab")
			(effects
				(font
					(size 0.7 0.7)
					(thickness 0.15)
				)
				(justify right top)
			)
		)
		(pad "1" smd roundrect
			(at -0.48 0 180)
			(size 0.59 0.64)
			(layers "F.Cu" "F.Mask" "F.Paste")
			(roundrect_rratio 0.25)
			(net 109 "Net-(C816-Pad2)")
			(pintype "passive")
		)
		(pad "2" smd roundrect
			(at 0.48 0 180)
			(size 0.59 0.64)
			(layers "F.Cu" "F.Mask" "F.Paste")
			(roundrect_rratio 0.25)
			(net 100 "Net-(C811-Pad2)")
			(pintype "passive")
		)
	)
	(footprint "antmicro-footprints:TP_SMD_0.75mm"
		(layer "F.Cu")
		(at 88.09 131.94 180)
		(property "Reference" "TP913"
			(at -0.18 4.11 0)
			(layer "F.SilkS")
			(effects
				(font
					(size 0.7 0.7)
					(thickness 0.15)
				)
				(justify right bottom)
			)
		)
		(property "Value" "TP_0.75mm_SMD"
			(at 0 1.2 0)
			(layer "F.Fab")
			(effects
				(font
					(size 0.7 0.7)
					(thickness 0.15)
				)
				(justify right bottom)
			)
		)
		(property "MPN" ""
			(at 0 0 180)
			(unlocked yes)
			(layer "F.Fab")
			(hide yes)
			(effects
				(font
					(size 1 1)
					(thickness 0.15)
				)
			)
		)
		(property "Manufacturer" ""
			(at 0 0 180)
			(unlocked yes)
			(layer "F.Fab")
			(hide yes)
			(effects
				(font
					(size 1 1)
					(thickness 0.15)
				)
			)
		)
		(property "Author" "Antmicro"
			(at 0 0 180)
			(unlocked yes)
			(layer "F.Fab")
			(hide yes)
			(effects
				(font
					(size 1 1)
					(thickness 0.15)
				)
			)
		)
		(property "License" "Apache-2.0"
			(at 0 0 180)
			(unlocked yes)
			(layer "F.Fab")
			(hide yes)
			(effects
				(font
					(size 1 1)
					(thickness 0.15)
				)
			)
		)
		(sheetname "/USB/")
		(sheetfile "usb.kicad_sch")
		(attr exclude_from_pos_files exclude_from_bom)
		(fp_circle
			(center 0 0)
			(end 0.475 0)
			(stroke
				(width 0.05)
				(type default)
			)
			(fill no)
			(layer "F.CrtYd")
		)
		(fp_text user "License: Apache-2.0"
			(at -0.4 5.101 180)
			(layer "F.Fab")
			(effects
				(font
					(size 0.7 0.7)
					(thickness 0.15)
				)
				(justify left bottom)
			)
		)
		(fp_text user "Author: Antmicro"
			(at -0.4 3.901 180)
			(layer "F.Fab")
			(effects
				(font
					(size 0.7 0.7)
					(thickness 0.15)
				)
				(justify left bottom)
			)
		)
		(fp_text user "${REFERENCE}"
			(at -0.4 2.7 180)
			(layer "F.Fab")
			(effects
				(font
					(size 0.7 0.7)
					(thickness 0.15)
				)
				(justify left bottom)
			)
		)
		(pad "1" smd circle
			(at 0 0 180)
			(size 0.75 0.75)
			(layers "F.Cu" "F.Mask")
			(net 438 "Net-(U905-PD2_SVBUS)")
			(pinfunction "1")
			(pintype "passive")
		)
	)
	(footprint "antmicro-footprints:TP_SMD_0.75mm"
		(layer "F.Cu")
		(at 83.292962 124.4665 180)
		(property "Reference" "TP903"
			(at -3.715 -0.11 0)
			(layer "F.SilkS")
			(effects
				(font
					(size 0.7 0.7)
					(thickness 0.15)
				)
				(justify right bottom)
			)
		)
		(property "Value" "TP_0.75mm_SMD"
			(at 0 1.2 0)
			(layer "F.Fab")
			(effects
				(font
					(size 0.7 0.7)
					(thickness 0.15)
				)
				(justify right bottom)
			)
		)
		(property "MPN" ""
			(at 0 0 180)
			(unlocked yes)
			(layer "F.Fab")
			(hide yes)
			(effects
				(font
					(size 1 1)
					(thickness 0.15)
				)
			)
		)
		(property "Manufacturer" ""
			(at 0 0 180)
			(unlocked yes)
			(layer "F.Fab")
			(hide yes)
			(effects
				(font
					(size 1 1)
					(thickness 0.15)
				)
			)
		)
		(property "Author" "Antmicro"
			(at 0 0 180)
			(unlocked yes)
			(layer "F.Fab")
			(hide yes)
			(effects
				(font
					(size 1 1)
					(thickness 0.15)
				)
			)
		)
		(property "License" "Apache-2.0"
			(at 0 0 180)
			(unlocked yes)
			(layer "F.Fab")
			(hide yes)
			(effects
				(font
					(size 1 1)
					(thickness 0.15)
				)
			)
		)
		(sheetname "/USB/")
		(sheetfile "usb.kicad_sch")
		(attr exclude_from_pos_files exclude_from_bom)
		(fp_circle
			(center 0 0)
			(end 0.475 0)
			(stroke
				(width 0.05)
				(type default)
			)
			(fill no)
			(layer "F.CrtYd")
		)
		(fp_text user "License: Apache-2.0"
			(at -0.4 5.101 180)
			(layer "F.Fab")
			(effects
				(font
					(size 0.7 0.7)
					(thickness 0.15)
				)
				(justify left bottom)
			)
		)
		(fp_text user "${REFERENCE}"
			(at -0.4 2.7 180)
			(layer "F.Fab")
			(effects
				(font
					(size 0.7 0.7)
					(thickness 0.15)
				)
				(justify left bottom)
			)
		)
		(fp_text user "Author: Antmicro"
			(at -0.4 3.901 180)
			(layer "F.Fab")
			(effects
				(font
					(size 0.7 0.7)
					(thickness 0.15)
				)
				(justify left bottom)
			)
		)
		(pad "1" smd circle
			(at 0 0 180)
			(size 0.75 0.75)
			(layers "F.Cu" "F.Mask")
			(net 113 "/USB/OUT_FTDI")
			(pinfunction "1")
			(pintype "passive")
		)
	)
	(footprint "antmicro-footprints:R_0402_1005Metric"
		(layer "F.Cu")
		(at 54.827962 132.7765)
		(descr "Resistor SMD 0402")
		(tags "resistor SMD 0402")
		(property "Reference" "R415"
			(at -1.215446 -5.279197 0)
			(layer "F.SilkS")
			(effects
				(font
					(size 0.7 0.7)
					(thickness 0.15)
				)
				(justify left bottom)
			)
		)
		(property "Value" "R_470k_0402"
			(at -1.011843 1.772047 0)
			(layer "F.Fab")
			(effects
				(font
					(size 0.7 0.7)
					(thickness 0.15)
				)
				(justify left bottom)
			)
		)
		(property "Datasheet" "https://www.bourns.com/docs/product-datasheets/cr.pdf"
			(at 0 0 0)
			(layer "F.Fab")
			(hide yes)
			(effects
				(font
					(size 1.27 1.27)
					(thickness 0.15)
				)
			)
		)
		(property "Manufacturer" "Bourns"
			(at 0 0 0)
			(unlocked yes)
			(layer "F.Fab")
			(hide yes)
			(effects
				(font
					(size 1 1)
					(thickness 0.15)
				)
			)
		)
		(property "MPN" "CR0402-FX-4703GLF"
			(at 0 0 0)
			(unlocked yes)
			(layer "F.Fab")
			(hide yes)
			(effects
				(font
					(size 1 1)
					(thickness 0.15)
				)
			)
		)
		(property "Val" "470k"
			(at 0 0 0)
			(unlocked yes)
			(layer "F.Fab")
			(hide yes)
			(effects
				(font
					(size 1 1)
					(thickness 0.15)
				)
			)
		)
		(property "License" "Apache-2.0"
			(at 0 0 0)
			(unlocked yes)
			(layer "F.Fab")
			(hide yes)
			(effects
				(font
					(size 1 1)
					(thickness 0.15)
				)
			)
		)
		(property "Author" "Antmicro"
			(at 0 0 0)
			(unlocked yes)
			(layer "F.Fab")
			(hide yes)
			(effects
				(font
					(size 1 1)
					(thickness 0.15)
				)
			)
		)
		(property "Tolerance" "1%"
			(at 0 0 0)
			(unlocked yes)
			(layer "F.Fab")
			(hide yes)
			(effects
				(font
					(size 1 1)
					(thickness 0.15)
				)
			)
		)
		(sheetname "/Ethernet/")
		(sheetfile "ethernet.kicad_sch")
		(attr smd)
		(fp_rect
			(start -0.925 -0.47)
			(end 0.925 0.47)
			(stroke
				(width 0.05)
				(type default)
			)
			(fill no)
			(layer "F.CrtYd")
		)
		(fp_rect
			(start -0.5 -0.25)
			(end 0.5 0.25)
			(stroke
				(width 0.15)
				(type solid)
			)
			(fill no)
			(layer "F.Fab")
		)
		(fp_text user "Author: Antmicro"
			(at -0.95 4.169 0)
			(layer "F.Fab")
			(effects
				(font
					(size 0.7 0.7)
					(thickness 0.15)
				)
				(justify left bottom)
			)
		)
		(fp_text user "License: Apache-2.0"
			(at -0.95 5.169 0)
			(layer "F.Fab")
			(effects
				(font
					(size 0.7 0.7)
					(thickness 0.15)
				)
				(justify left bottom)
			)
		)
		(fp_text user "${REFERENCE}"
			(at -0.95 3.168 0)
			(layer "F.Fab")
			(effects
				(font
					(size 0.7 0.7)
					(thickness 0.15)
				)
				(justify left bottom)
			)
		)
		(pad "1" smd roundrect
			(at -0.48 0)
			(size 0.59 0.64)
			(layers "F.Cu" "F.Mask" "F.Paste")
			(roundrect_rratio 0.25)
			(net 339 "/Ethernet/POE_ACTIVE")
			(pintype "passive")
		)
		(pad "2" smd roundrect
			(at 0.48 0)
			(size 0.59 0.64)
			(layers "F.Cu" "F.Mask" "F.Paste")
			(roundrect_rratio 0.25)
			(net 33 "/Ethernet/VDD")
			(pintype "passive")
		)
	)
	(footprint "antmicro-footprints:C_0402_1005Metric"
		(layer "F.Cu")
		(at 75.877962 122.8265)
		(descr "Capacitor SMD 0402")
		(tags "capacitor SMD 0402")
		(property "Reference" "C902"
			(at -1.97 2.25 90)
			(layer "F.SilkS")
			(effects
				(font
					(size 0.7 0.7)
					(thickness 0.15)
				)
				(justify left bottom)
			)
		)
		(property "Value" "C_100n_0402"
			(at -1.022927 2.155213 0)
			(layer "F.Fab")
			(effects
				(font
					(size 0.7 0.7)
					(thickness 0.15)
				)
				(justify left bottom)
			)
		)
		(property "Datasheet" "https://www.murata.com/products/productdetail?partno=GRM155R61H104KE14%23"
			(at 0 0 0)
			(layer "F.Fab")
			(hide yes)
			(effects
				(font
					(size 1.27 1.27)
					(thickness 0.15)
				)
			)
		)
		(property "MPN" "GRM155R61H104KE14D"
			(at 0 0 0)
			(unlocked yes)
			(layer "F.Fab")
			(hide yes)
			(effects
				(font
					(size 1 1)
					(thickness 0.15)
				)
			)
		)
		(property "Manufacturer" "Murata"
			(at 0 0 0)
			(unlocked yes)
			(layer "F.Fab")
			(hide yes)
			(effects
				(font
					(size 1 1)
					(thickness 0.15)
				)
			)
		)
		(property "License" "Apache-2.0"
			(at 0 0 0)
			(unlocked yes)
			(layer "F.Fab")
			(hide yes)
			(effects
				(font
					(size 1 1)
					(thickness 0.15)
				)
			)
		)
		(property "Author" "Antmicro"
			(at 0 0 0)
			(unlocked yes)
			(layer "F.Fab")
			(hide yes)
			(effects
				(font
					(size 1 1)
					(thickness 0.15)
				)
			)
		)
		(property "Val" "100n"
			(at 0 0 0)
			(unlocked yes)
			(layer "F.Fab")
			(hide yes)
			(effects
				(font
					(size 1 1)
					(thickness 0.15)
				)
			)
		)
		(property "Voltage" "50V"
			(at 0 0 0)
			(unlocked yes)
			(layer "F.Fab")
			(hide yes)
			(effects
				(font
					(size 1 1)
					(thickness 0.15)
				)
			)
		)
		(property "Dielectric" "X5R"
			(at 0 0 0)
			(unlocked yes)
			(layer "F.Fab")
			(hide yes)
			(effects
				(font
					(size 1 1)
					(thickness 0.15)
				)
			)
		)
		(sheetname "/USB/")
		(sheetfile "usb.kicad_sch")
		(attr smd)
		(fp_rect
			(start -0.925 -0.47)
			(end 0.925 0.47)
			(stroke
				(width 0.05)
				(type default)
			)
			(fill no)
			(layer "F.CrtYd")
		)
		(fp_line
			(start -0.494 -0.25)
			(end 0.504 -0.25)
			(stroke
				(width 0.15)
				(type solid)
			)
			(layer "F.Fab")
		)
		(fp_line
			(start -0.494 0.248)
			(end -0.494 -0.25)
			(stroke
				(width 0.15)
				(type solid)
			)
			(layer "F.Fab")
		)
		(fp_line
			(start 0.504 -0.25)
			(end 0.504 0.248)
			(stroke
				(width 0.15)
				(type solid)
			)
			(layer "F.Fab")
		)
		(fp_line
			(start 0.504 0.248)
			(end -0.494 0.248)
			(stroke
				(width 0.15)
				(type solid)
			)
			(layer "F.Fab")
		)
		(fp_text user "Author: Antmicro"
			(at -0.939 3.399 0)
			(layer "F.Fab")
			(effects
				(font
					(size 0.7 0.7)
					(thickness 0.15)
				)
				(justify left bottom)
			)
		)
		(fp_text user "${REFERENCE}"
			(at -0.939 4.599 0)
			(layer "F.Fab")
			(effects
				(font
					(size 0.7 0.7)
					(thickness 0.15)
				)
				(justify left bottom)
			)
		)
		(fp_text user "License: Apache-2.0"
			(at -0.939 5.799 0)
			(layer "F.Fab")
			(effects
				(font
					(size 0.7 0.7)
					(thickness 0.15)
				)
				(justify left bottom)
			)
		)
		(pad "1" smd roundrect
			(at -0.48 0)
			(size 0.59 0.64)
			(layers "F.Cu" "F.Mask" "F.Paste")
			(roundrect_rratio 0.25)
			(net 3 "GND")
			(pintype "passive")
		)
		(pad "2" smd roundrect
			(at 0.48 0)
			(size 0.59 0.64)
			(layers "F.Cu" "F.Mask" "F.Paste")
			(roundrect_rratio 0.25)
			(net 26 "/USB/USBD_VBUS")
			(pintype "passive")
		)
	)
	(footprint "antmicro-footprints:C_0402_1005Metric"
		(layer "F.Cu")
		(at 133.317962 123.7915)
		(descr "Capacitor SMD 0402")
		(tags "capacitor SMD 0402")
		(property "Reference" "C201"
			(at -1.2 8.105 0)
			(layer "F.SilkS")
			(effects
				(font
					(size 0.7 0.7)
					(thickness 0.15)
				)
				(justify left bottom)
			)
		)
		(property "Value" "C_100n_0402"
			(at -1.022927 2.155213 0)
			(layer "F.Fab")
			(effects
				(font
					(size 0.7 0.7)
					(thickness 0.15)
				)
				(justify left bottom)
			)
		)
		(property "Datasheet" "https://www.murata.com/products/productdetail?partno=GRM155R61H104KE14%23"
			(at 0 0 0)
			(layer "F.Fab")
			(hide yes)
			(effects
				(font
					(size 1.27 1.27)
					(thickness 0.15)
				)
			)
		)
		(property "Manufacturer" "Murata"
			(at 0 0 0)
			(unlocked yes)
			(layer "F.Fab")
			(hide yes)
			(effects
				(font
					(size 1 1)
					(thickness 0.15)
				)
			)
		)
		(property "MPN" "GRM155R61H104KE14D"
			(at 0 0 0)
			(unlocked yes)
			(layer "F.Fab")
			(hide yes)
			(effects
				(font
					(size 1 1)
					(thickness 0.15)
				)
			)
		)
		(property "Val" "100n"
			(at 0 0 0)
			(unlocked yes)
			(layer "F.Fab")
			(hide yes)
			(effects
				(font
					(size 1 1)
					(thickness 0.15)
				)
			)
		)
		(property "License" "Apache-2.0"
			(at 0 0 0)
			(unlocked yes)
			(layer "F.Fab")
			(hide yes)
			(effects
				(font
					(size 1 1)
					(thickness 0.15)
				)
			)
		)
		(property "Author" "Antmicro"
			(at 0 0 0)
			(unlocked yes)
			(layer "F.Fab")
			(hide yes)
			(effects
				(font
					(size 1 1)
					(thickness 0.15)
				)
			)
		)
		(property "Voltage" "50V"
			(at 0 0 0)
			(unlocked yes)
			(layer "F.Fab")
			(hide yes)
			(effects
				(font
					(size 1 1)
					(thickness 0.15)
				)
			)
		)
		(property "Dielectric" "X5R"
			(at 0 0 0)
			(unlocked yes)
			(layer "F.Fab")
			(hide yes)
			(effects
				(font
					(size 1 1)
					(thickness 0.15)
				)
			)
		)
		(sheetname "/Compute module/")
		(sheetfile "compute-module.kicad_sch")
		(attr smd)
		(fp_rect
			(start -0.925 -0.47)
			(end 0.925 0.47)
			(stroke
				(width 0.05)
				(type default)
			)
			(fill no)
			(layer "F.CrtYd")
		)
		(fp_line
			(start -0.494 -0.25)
			(end 0.504 -0.25)
			(stroke
				(width 0.15)
				(type solid)
			)
			(layer "F.Fab")
		)
		(fp_line
			(start -0.494 0.248)
			(end -0.494 -0.25)
			(stroke
				(width 0.15)
				(type solid)
			)
			(layer "F.Fab")
		)
		(fp_line
			(start 0.504 -0.25)
			(end 0.504 0.248)
			(stroke
				(width 0.15)
				(type solid)
			)
			(layer "F.Fab")
		)
		(fp_line
			(start 0.504 0.248)
			(end -0.494 0.248)
			(stroke
				(width 0.15)
				(type solid)
			)
			(layer "F.Fab")
		)
		(fp_text user "License: Apache-2.0"
			(at -0.939 5.799 0)
			(layer "F.Fab")
			(effects
				(font
					(size 0.7 0.7)
					(thickness 0.15)
				)
				(justify left bottom)
			)
		)
		(fp_text user "${REFERENCE}"
			(at -0.939 4.599 0)
			(layer "F.Fab")
			(effects
				(font
					(size 0.7 0.7)
					(thickness 0.15)
				)
				(justify left bottom)
			)
		)
		(fp_text user "Author: Antmicro"
			(at -0.939 3.399 0)
			(layer "F.Fab")
			(effects
				(font
					(size 0.7 0.7)
					(thickness 0.15)
				)
				(justify left bottom)
			)
		)
		(pad "1" smd roundrect
			(at -0.48 0)
			(size 0.59 0.64)
			(layers "F.Cu" "F.Mask" "F.Paste")
			(roundrect_rratio 0.25)
			(net 3 "GND")
			(pintype "passive")
		)
		(pad "2" smd roundrect
			(at 0.48 0)
			(size 0.59 0.64)
			(layers "F.Cu" "F.Mask" "F.Paste")
			(roundrect_rratio 0.25)
			(net 2 "Net-(D203-A)")
			(pintype "passive")
		)
	)
)
